(kicad_pcb
	(version 20260206)
	(generator "pcbnew")
	(generator_version "10.0")
	(general
		(thickness 1.6)
		(legacy_teardrops no)
	)
	(paper "A4")
	(title_block
		(title "Wiwynn_Tioga_Pass_MB.brd")
		(comment 1 "Tioga Pass / footprint 190 of 4770 (U2D1), pads 1323-1428 of 3647")
	)
	(layers
		(0 "F.Cu" signal "TOP")
		(4 "In1.Cu" signal "L2GND")
		(6 "In2.Cu" signal "L3")
		(8 "In3.Cu" signal "L4GND")
		(10 "In4.Cu" signal "L5")
		(12 "In5.Cu" signal "L6GND")
		(14 "In6.Cu" signal "L7VCC")
		(16 "In7.Cu" signal "L8VCC")
		(18 "In8.Cu" signal "L9GND")
		(20 "In9.Cu" signal "L10")
		(22 "In10.Cu" signal "L11GND")
		(24 "In11.Cu" signal "L12")
		(26 "In12.Cu" signal "L13GND")
		(2 "B.Cu" signal "BOTTOM")
		(9 "F.Adhes" user "F.Adhesive")
		(11 "B.Adhes" user "B.Adhesive")
		(13 "F.Paste" user "Package Geometry/Pastemask Top")
		(15 "B.Paste" user "Package Geometry/Pastemask Bottom")
		(5 "F.SilkS" user "Ref Des/Silkscreen Top")
		(7 "B.SilkS" user "Ref Des/Silkscreen Bottom")
		(1 "F.Mask" user "Board Geometry/Soldermask Top")
		(3 "B.Mask" user "Board Geometry/Soldermask Bottom")
		(17 "Dwgs.User" user "User.Drawings")
		(19 "Cmts.User" user "User.Comments")
		(21 "Eco1.User" user "User.Eco1")
		(23 "Eco2.User" user "User.Eco2")
		(25 "Edge.Cuts" user "Board Geometry/Outline")
		(27 "Margin" user)
		(31 "F.CrtYd" user "Package Geometry/Place Bound Top")
		(29 "B.CrtYd" user "Package Geometry/Place Bound Bottom")
		(35 "F.Fab" user "Ref Des/Assembly Top")
		(33 "B.Fab" user "Ref Des/Assembly Bottom")
	)
	(footprint ""
		(layer "F.Cu")
		(at 104.99979 -76.550012 180)
		(property "Reference" "U2D1"
			(at 25.19299 30.484318 0)
			(unlocked yes)
			(layer "F.SilkS")
			(effects
				(font
					(size 0.7874 0.5842)
					(thickness 0.1524)
				)
			)
		)
		(property "Value" ""
			(at 0 0 180)
			(layer "F.Fab")
			(effects
				(font
					(size 1.27 1.27)
				)
			)
		)
		(duplicate_pad_numbers_are_jumpers no)
		(pad "CA84" smd custom
			(at 35.533584 2.814828 270)
			(size 0.10795 0.10795)
			(layers "F.Cu" "F.Mask" "F.Paste")
			(net "PVCCIN_CPU1")
			(options
				(clearance outline)
				(anchor circle)
			)
			(primitives
				(gr_poly
					(pts
						(arc
							(start 0.2159 -0.0381)
							(mid 0 -0.254)
							(end -0.2159 -0.0381)
						)
						(arc
							(start -0.2159 0.0381)
							(mid 0 0.254)
							(end 0.2159 0.0381)
						)
					)
					(width 0)
					(fill yes)
				)
			)
		)
		(pad "CB3" smd circle
			(at -35.533584 5.109972)
			(size 0.4318 0.4318)
			(layers "F.Cu" "F.Mask" "F.Paste")
			(net "TP_P3E_CPU1_PE2_RSR_TXN<9>")
		)
		(pad "CB5" smd circle
			(at -33.816544 5.109972)
			(size 0.4318 0.4318)
			(layers "F.Cu" "F.Mask" "F.Paste")
			(net "TP_CPU1_RSVD_113")
		)
		(pad "CB7" smd circle
			(at -32.099504 5.109972)
			(size 0.4318 0.4318)
			(layers "F.Cu" "F.Mask" "F.Paste")
			(net "GND")
		)
		(pad "CB9" smd circle
			(at -30.382464 5.109972)
			(size 0.4318 0.4318)
			(layers "F.Cu" "F.Mask" "F.Paste")
			(net "GND")
		)
		(pad "CB11" smd circle
			(at -28.665424 5.109972)
			(size 0.4318 0.4318)
			(layers "F.Cu" "F.Mask" "F.Paste")
			(net "TP_CPU1_UPI2_RSVD_DN20")
		)
		(pad "CB13" smd circle
			(at -26.948384 5.109972)
			(size 0.4318 0.4318)
			(layers "F.Cu" "F.Mask" "F.Paste")
			(net "PVCCIO_CPU1")
		)
		(pad "CB15" smd circle
			(at -25.231598 5.109972)
			(size 0.4318 0.4318)
			(layers "F.Cu" "F.Mask" "F.Paste")
			(net "GND")
		)
		(pad "CB17" smd circle
			(at -23.514558 5.109972)
			(size 0.4318 0.4318)
			(layers "F.Cu" "F.Mask" "F.Paste")
			(net "PVCCIO_CPU1")
		)
		(pad "CB19" smd circle
			(at -21.797518 5.109972)
			(size 0.4318 0.4318)
			(layers "F.Cu" "F.Mask" "F.Paste")
			(net "PVCCMCP_CPU1")
		)
		(pad "CB21" smd circle
			(at -20.080478 5.109972)
			(size 0.4318 0.4318)
			(layers "F.Cu" "F.Mask" "F.Paste")
			(net "PVCCMCP_CPU1")
		)
		(pad "CB23" smd circle
			(at -18.363438 5.109972)
			(size 0.4318 0.4318)
			(layers "F.Cu" "F.Mask" "F.Paste")
			(net "JTAG_MCP_TCK")
		)
		(pad "CB25" smd circle
			(at -16.646398 5.109972)
			(size 0.4318 0.4318)
			(layers "F.Cu" "F.Mask" "F.Paste")
			(net "TP_CPU1_RSVD_114")
		)
		(pad "CB27" smd circle
			(at -14.929612 5.109972)
			(size 0.4318 0.4318)
			(layers "F.Cu" "F.Mask" "F.Paste")
			(net "GND")
		)
		(pad "CB61" smd circle
			(at 15.787878 3.309874)
			(size 0.4318 0.4318)
			(layers "F.Cu" "F.Mask" "F.Paste")
			(net "PVCCIN_CPU1")
		)
		(pad "CB63" smd circle
			(at 17.504918 3.309874)
			(size 0.4318 0.4318)
			(layers "F.Cu" "F.Mask" "F.Paste")
			(net "GND")
		)
		(pad "CB65" smd circle
			(at 19.221958 3.309874)
			(size 0.4318 0.4318)
			(layers "F.Cu" "F.Mask" "F.Paste")
			(net "PVSA_CPU1")
		)
		(pad "CB67" smd circle
			(at 20.938998 3.309874)
			(size 0.4318 0.4318)
			(layers "F.Cu" "F.Mask" "F.Paste")
			(net "PVSA_CPU1")
		)
		(pad "CB69" smd circle
			(at 22.656038 3.309874)
			(size 0.4318 0.4318)
			(layers "F.Cu" "F.Mask" "F.Paste")
			(net "PVSA_CPU1")
		)
		(pad "CB71" smd circle
			(at 24.373078 3.309874)
			(size 0.4318 0.4318)
			(layers "F.Cu" "F.Mask" "F.Paste")
			(net "GND")
		)
		(pad "CB73" smd circle
			(at 26.090118 3.309874)
			(size 0.4318 0.4318)
			(layers "F.Cu" "F.Mask" "F.Paste")
			(net "PVCCIN_CPU1")
		)
		(pad "CB75" smd circle
			(at 27.806904 3.309874)
			(size 0.4318 0.4318)
			(layers "F.Cu" "F.Mask" "F.Paste")
			(net "PVCCIN_CPU1")
		)
		(pad "CB77" smd circle
			(at 29.523944 3.309874)
			(size 0.4318 0.4318)
			(layers "F.Cu" "F.Mask" "F.Paste")
			(net "PVCCIN_CPU1")
		)
		(pad "CB79" smd circle
			(at 31.240984 3.309874)
			(size 0.4318 0.4318)
			(layers "F.Cu" "F.Mask" "F.Paste")
			(net "PVCCIN_CPU1")
		)
		(pad "CB81" smd circle
			(at 32.958024 3.309874)
			(size 0.4318 0.4318)
			(layers "F.Cu" "F.Mask" "F.Paste")
			(net "PVCCIN_CPU1")
		)
		(pad "CB83" smd circle
			(at 34.675064 3.309874)
			(size 0.4318 0.4318)
			(layers "F.Cu" "F.Mask" "F.Paste")
			(net "PVCCIN_CPU1")
		)
		(pad "CC2" smd custom
			(at -36.392104 5.605272 90)
			(size 0.10795 0.10795)
			(layers "F.Cu" "F.Mask" "F.Paste")
			(net "TP_P3E_CPU1_PE2_RSR_TXN<8>")
			(options
				(clearance outline)
				(anchor circle)
			)
			(primitives
				(gr_poly
					(pts
						(arc
							(start 0.2159 -0.0381)
							(mid 0 -0.254)
							(end -0.2159 -0.0381)
						)
						(arc
							(start -0.2159 0.0381)
							(mid 0 0.254)
							(end 0.2159 0.0381)
						)
					)
					(width 0)
					(fill yes)
				)
			)
		)
		(pad "CC4" smd circle
			(at -34.675064 5.605272)
			(size 0.4318 0.4318)
			(layers "F.Cu" "F.Mask" "F.Paste")
			(net "GND")
		)
		(pad "CC6" smd circle
			(at -32.958024 5.605272)
			(size 0.4318 0.4318)
			(layers "F.Cu" "F.Mask" "F.Paste")
			(net "TP_CPU1_RSVD_111")
		)
		(pad "CC8" smd circle
			(at -31.240984 5.605272)
			(size 0.4318 0.4318)
			(layers "F.Cu" "F.Mask" "F.Paste")
			(net "TP_P3E_CPU1_PE2_RSR_RXP<7>")
		)
		(pad "CC10" smd circle
			(at -29.523944 5.605272)
			(size 0.4318 0.4318)
			(layers "F.Cu" "F.Mask" "F.Paste")
			(net "TP_CPU1_UPI2_RSVD_DM21")
		)
		(pad "CC12" smd circle
			(at -27.806904 5.605272)
			(size 0.4318 0.4318)
			(layers "F.Cu" "F.Mask" "F.Paste")
			(net "TP_CPU1_UPI2_RSVD_DT21")
		)
		(pad "CC14" smd circle
			(at -26.090118 5.605272)
			(size 0.4318 0.4318)
			(layers "F.Cu" "F.Mask" "F.Paste")
			(net "GND")
		)
		(pad "CC16" smd circle
			(at -24.373078 5.605272)
			(size 0.4318 0.4318)
			(layers "F.Cu" "F.Mask" "F.Paste")
			(net "GND")
		)
		(pad "CC18" smd circle
			(at -22.656038 5.605272)
			(size 0.4318 0.4318)
			(layers "F.Cu" "F.Mask" "F.Paste")
			(net "GND")
		)
		(pad "CC20" smd circle
			(at -20.938998 5.605272)
			(size 0.4318 0.4318)
			(layers "F.Cu" "F.Mask" "F.Paste")
			(net "PVCCMCP_CPU1")
		)
		(pad "CC22" smd circle
			(at -19.221958 5.605272)
			(size 0.4318 0.4318)
			(layers "F.Cu" "F.Mask" "F.Paste")
			(net "JTAG_MCP_CPU1_TDO")
		)
		(pad "CC24" smd circle
			(at -17.504918 5.605272)
			(size 0.4318 0.4318)
			(layers "F.Cu" "F.Mask" "F.Paste")
			(net "GND")
		)
		(pad "CC26" smd circle
			(at -15.787878 5.605272)
			(size 0.4318 0.4318)
			(layers "F.Cu" "F.Mask" "F.Paste")
			(net "PVCCIO_CPU1")
		)
		(pad "CC60" smd circle
			(at 14.929612 3.805428)
			(size 0.508 0.508)
			(layers "F.Cu" "F.Mask" "F.Paste")
			(net "PVCCIN_CPU1")
		)
		(pad "CC62" smd circle
			(at 16.646398 3.805428)
			(size 0.4318 0.4318)
			(layers "F.Cu" "F.Mask" "F.Paste")
			(net "PVCCIN_CPU1")
		)
		(pad "CC64" smd circle
			(at 18.363438 3.805428)
			(size 0.4318 0.4318)
			(layers "F.Cu" "F.Mask" "F.Paste")
			(net "GND")
		)
		(pad "CC66" smd circle
			(at 20.080478 3.805428)
			(size 0.4318 0.4318)
			(layers "F.Cu" "F.Mask" "F.Paste")
			(net "PVSA_CPU1")
		)
		(pad "CC68" smd circle
			(at 21.797518 3.805428)
			(size 0.4318 0.4318)
			(layers "F.Cu" "F.Mask" "F.Paste")
			(net "PVSA_CPU1")
		)
		(pad "CC70" smd circle
			(at 23.514558 3.805428)
			(size 0.4318 0.4318)
			(layers "F.Cu" "F.Mask" "F.Paste")
			(net "PVSA_CPU1")
		)
		(pad "CC72" smd circle
			(at 25.231598 3.805428)
			(size 0.4318 0.4318)
			(layers "F.Cu" "F.Mask" "F.Paste")
			(net "GND")
		)
		(pad "CC74" smd circle
			(at 26.948384 3.805428)
			(size 0.4318 0.4318)
			(layers "F.Cu" "F.Mask" "F.Paste")
			(net "GND")
		)
		(pad "CC76" smd circle
			(at 28.665424 3.805428)
			(size 0.4318 0.4318)
			(layers "F.Cu" "F.Mask" "F.Paste")
			(net "GND")
		)
		(pad "CC78" smd circle
			(at 30.382464 3.805428)
			(size 0.4318 0.4318)
			(layers "F.Cu" "F.Mask" "F.Paste")
			(net "GND")
		)
		(pad "CC80" smd circle
			(at 32.099504 3.805428)
			(size 0.4318 0.4318)
			(layers "F.Cu" "F.Mask" "F.Paste")
			(net "GND")
		)
		(pad "CC82" smd circle
			(at 33.816544 3.805428)
			(size 0.4318 0.4318)
			(layers "F.Cu" "F.Mask" "F.Paste")
			(net "GND")
		)
		(pad "CC84" smd custom
			(at 35.533584 3.805428 270)
			(size 0.10795 0.10795)
			(layers "F.Cu" "F.Mask" "F.Paste")
			(net "PVCCIN_CPU1")
			(options
				(clearance outline)
				(anchor circle)
			)
			(primitives
				(gr_poly
					(pts
						(arc
							(start 0.2159 -0.0381)
							(mid 0 -0.254)
							(end -0.2159 -0.0381)
						)
						(arc
							(start -0.2159 0.0381)
							(mid 0 0.254)
							(end 0.2159 0.0381)
						)
					)
					(width 0)
					(fill yes)
				)
			)
		)
		(pad "CD3" smd circle
			(at -35.533584 6.100572)
			(size 0.4318 0.4318)
			(layers "F.Cu" "F.Mask" "F.Paste")
			(net "TP_P3E_CPU1_PE2_RSR_TXP<8>")
		)
		(pad "CD5" smd circle
			(at -33.816544 6.100572)
			(size 0.4318 0.4318)
			(layers "F.Cu" "F.Mask" "F.Paste")
			(net "GND")
		)
		(pad "CD7" smd circle
			(at -32.099504 6.100572)
			(size 0.4318 0.4318)
			(layers "F.Cu" "F.Mask" "F.Paste")
			(net "TP_P3E_CPU1_PE2_RSR_RXP<6>")
		)
		(pad "CD9" smd circle
			(at -30.382464 6.100572)
			(size 0.4318 0.4318)
			(layers "F.Cu" "F.Mask" "F.Paste")
			(net "PVCCIO_CPU1")
		)
		(pad "CD11" smd circle
			(at -28.665424 6.100572)
			(size 0.4318 0.4318)
			(layers "F.Cu" "F.Mask" "F.Paste")
			(net "TP_CPU1_UPI2_RSVD_DK19")
		)
		(pad "CD13" smd circle
			(at -26.948384 6.100572)
			(size 0.4318 0.4318)
			(layers "F.Cu" "F.Mask" "F.Paste")
			(net "GND")
		)
		(pad "CD15" smd circle
			(at -25.231598 6.100572)
			(size 0.4318 0.4318)
			(layers "F.Cu" "F.Mask" "F.Paste")
			(net "GND")
		)
		(pad "CD17" smd circle
			(at -23.514558 6.100572)
			(size 0.4318 0.4318)
			(layers "F.Cu" "F.Mask" "F.Paste")
			(net "GND")
		)
		(pad "CD19" smd circle
			(at -21.797518 6.100572)
			(size 0.4318 0.4318)
			(layers "F.Cu" "F.Mask" "F.Paste")
			(net "PVCCMCP_CPU1")
		)
		(pad "CD21" smd circle
			(at -20.080478 6.100572)
			(size 0.4318 0.4318)
			(layers "F.Cu" "F.Mask" "F.Paste")
			(net "PVCCMCP_CPU1")
		)
		(pad "CD23" smd circle
			(at -18.363438 6.100572)
			(size 0.4318 0.4318)
			(layers "F.Cu" "F.Mask" "F.Paste")
			(net "JTAG_MCP_TRST_N")
		)
		(pad "CD25" smd circle
			(at -16.646398 6.100572)
			(size 0.4318 0.4318)
			(layers "F.Cu" "F.Mask" "F.Paste")
			(net "TP_CPU1_RSVD_108")
		)
		(pad "CD27" smd circle
			(at -14.929612 6.100572)
			(size 0.4318 0.4318)
			(layers "F.Cu" "F.Mask" "F.Paste")
			(net "PVCCIO_CPU1")
		)
		(pad "CD61" smd circle
			(at 15.787878 4.300474)
			(size 0.4318 0.4318)
			(layers "F.Cu" "F.Mask" "F.Paste")
			(net "PVCCIN_CPU1")
		)
		(pad "CD63" smd circle
			(at 17.504918 4.300474)
			(size 0.4318 0.4318)
			(layers "F.Cu" "F.Mask" "F.Paste")
			(net "GND")
		)
		(pad "CD65" smd circle
			(at 19.221958 4.300474)
			(size 0.4318 0.4318)
			(layers "F.Cu" "F.Mask" "F.Paste")
			(net "PVSA_CPU1")
		)
		(pad "CD67" smd circle
			(at 20.938998 4.300474)
			(size 0.4318 0.4318)
			(layers "F.Cu" "F.Mask" "F.Paste")
			(net "PVSA_CPU1")
		)
		(pad "CD69" smd circle
			(at 22.656038 4.300474)
			(size 0.4318 0.4318)
			(layers "F.Cu" "F.Mask" "F.Paste")
			(net "PVSA_CPU1")
		)
		(pad "CD71" smd circle
			(at 24.373078 4.300474)
			(size 0.4318 0.4318)
			(layers "F.Cu" "F.Mask" "F.Paste")
			(net "PVSA_CPU1")
		)
		(pad "CD73" smd circle
			(at 26.090118 4.300474)
			(size 0.4318 0.4318)
			(layers "F.Cu" "F.Mask" "F.Paste")
			(net "GND")
		)
		(pad "CD75" smd circle
			(at 27.806904 4.300474)
			(size 0.4318 0.4318)
			(layers "F.Cu" "F.Mask" "F.Paste")
			(net "GND")
		)
		(pad "CD77" smd circle
			(at 29.523944 4.300474)
			(size 0.4318 0.4318)
			(layers "F.Cu" "F.Mask" "F.Paste")
			(net "GND")
		)
		(pad "CD79" smd circle
			(at 31.240984 4.300474)
			(size 0.4318 0.4318)
			(layers "F.Cu" "F.Mask" "F.Paste")
			(net "GND")
		)
		(pad "CD81" smd circle
			(at 32.958024 4.300474)
			(size 0.4318 0.4318)
			(layers "F.Cu" "F.Mask" "F.Paste")
			(net "GND")
		)
		(pad "CD83" smd circle
			(at 34.675064 4.300474)
			(size 0.4318 0.4318)
			(layers "F.Cu" "F.Mask" "F.Paste")
			(net "PVCCIN_CPU1")
		)
		(pad "CD85" smd custom
			(at 36.392104 4.300474 270)
			(size 0.10795 0.10795)
			(layers "F.Cu" "F.Mask" "F.Paste")
			(net "PVCCIN_CPU1")
			(options
				(clearance outline)
				(anchor circle)
			)
			(primitives
				(gr_poly
					(pts
						(arc
							(start 0.2159 -0.0381)
							(mid 0 -0.254)
							(end -0.2159 -0.0381)
						)
						(arc
							(start -0.2159 0.0381)
							(mid 0 0.254)
							(end 0.2159 0.0381)
						)
					)
					(width 0)
					(fill yes)
				)
			)
		)
		(pad "CE2" smd custom
			(at -36.392104 6.596126 90)
			(size 0.10795 0.10795)
			(layers "F.Cu" "F.Mask" "F.Paste")
			(net "TP_P3E_CPU1_PE2_RSR_TXP<6>")
			(options
				(clearance outline)
				(anchor circle)
			)
			(primitives
				(gr_poly
					(pts
						(arc
							(start 0.2159 -0.0381)
							(mid 0 -0.254)
							(end -0.2159 -0.0381)
						)
						(arc
							(start -0.2159 0.0381)
							(mid 0 0.254)
							(end 0.2159 0.0381)
						)
					)
					(width 0)
					(fill yes)
				)
			)
		)
		(pad "CE4" smd circle
			(at -34.675064 6.596126)
			(size 0.4318 0.4318)
			(layers "F.Cu" "F.Mask" "F.Paste")
			(net "TP_P3E_CPU1_PE2_RSR_TXP<7>")
		)
		(pad "CE6" smd circle
			(at -32.958024 6.596126)
			(size 0.4318 0.4318)
			(layers "F.Cu" "F.Mask" "F.Paste")
			(net "TP_P3E_CPU1_PE2_RSR_RXN<6>")
		)
		(pad "CE8" smd circle
			(at -31.240984 6.596126)
			(size 0.4318 0.4318)
			(layers "F.Cu" "F.Mask" "F.Paste")
			(net "TP_P3E_CPU1_PE2_RSR_RXN<7>")
		)
		(pad "CE10" smd circle
			(at -29.523944 6.596126)
			(size 0.4318 0.4318)
			(layers "F.Cu" "F.Mask" "F.Paste")
			(net "GND")
		)
		(pad "CE12" smd circle
			(at -27.806904 6.596126)
			(size 0.4318 0.4318)
			(layers "F.Cu" "F.Mask" "F.Paste")
			(net "TP_CPU1_UPI2_RSVD_DL20")
		)
		(pad "CE14" smd circle
			(at -26.090118 6.596126)
			(size 0.4318 0.4318)
			(layers "F.Cu" "F.Mask" "F.Paste")
			(net "GND")
		)
		(pad "CE16" smd circle
			(at -24.373078 6.596126)
			(size 0.4318 0.4318)
			(layers "F.Cu" "F.Mask" "F.Paste")
			(net "GND")
		)
		(pad "CE18" smd circle
			(at -22.656038 6.596126)
			(size 0.4318 0.4318)
			(layers "F.Cu" "F.Mask" "F.Paste")
			(net "PVCCIO_CPU1")
		)
		(pad "CE20" smd circle
			(at -20.938998 6.596126)
			(size 0.4318 0.4318)
			(layers "F.Cu" "F.Mask" "F.Paste")
			(net "GND")
		)
		(pad "CE22" smd circle
			(at -19.221958 6.596126)
			(size 0.4318 0.4318)
			(layers "F.Cu" "F.Mask" "F.Paste")
			(net "PVCCMCP_CPU1")
		)
		(pad "CE24" smd circle
			(at -17.504918 6.596126)
			(size 0.4318 0.4318)
			(layers "F.Cu" "F.Mask" "F.Paste")
			(net "JTAG_MCP_TMS")
		)
		(pad "CE26" smd circle
			(at -15.787878 6.596126)
			(size 0.4318 0.4318)
			(layers "F.Cu" "F.Mask" "F.Paste")
			(net "GND")
		)
		(pad "CE60" smd circle
			(at 14.929612 4.796028)
			(size 0.508 0.508)
			(layers "F.Cu" "F.Mask" "F.Paste")
			(net "PVCCIN_CPU1")
		)
		(pad "CE62" smd circle
			(at 16.646398 4.796028)
			(size 0.4318 0.4318)
			(layers "F.Cu" "F.Mask" "F.Paste")
			(net "GND")
		)
		(pad "CE64" smd circle
			(at 18.363438 4.796028)
			(size 0.4318 0.4318)
			(layers "F.Cu" "F.Mask" "F.Paste")
			(net "PVSA_CPU1")
		)
		(pad "CE66" smd circle
			(at 20.080478 4.796028)
			(size 0.4318 0.4318)
			(layers "F.Cu" "F.Mask" "F.Paste")
			(net "PVSA_CPU1")
		)
		(pad "CE68" smd circle
			(at 21.797518 4.796028)
			(size 0.4318 0.4318)
			(layers "F.Cu" "F.Mask" "F.Paste")
			(net "PVSA_CPU1")
		)
		(pad "CE70" smd circle
			(at 23.514558 4.796028)
			(size 0.4318 0.4318)
			(layers "F.Cu" "F.Mask" "F.Paste")
			(net "GND")
		)
		(pad "CE72" smd circle
			(at 25.231598 4.796028)
			(size 0.4318 0.4318)
			(layers "F.Cu" "F.Mask" "F.Paste")
			(net "PVSA_CPU1")
		)
		(pad "CE74" smd circle
			(at 26.948384 4.796028)
			(size 0.4318 0.4318)
			(layers "F.Cu" "F.Mask" "F.Paste")
			(net "PVSA_CPU1")
		)
		(pad "CE76" smd circle
			(at 28.665424 4.796028)
			(size 0.4318 0.4318)
			(layers "F.Cu" "F.Mask" "F.Paste")
			(net "VSENSE_PVSA_CPU1_SKT_VSEN")
		)
		(pad "CE78" smd circle
			(at 30.382464 4.796028)
			(size 0.4318 0.4318)
			(layers "F.Cu" "F.Mask" "F.Paste")
			(net "TP_CPU1_RSVD_106")
		)
		(pad "CE80" smd circle
			(at 32.099504 4.796028)
			(size 0.4318 0.4318)
			(layers "F.Cu" "F.Mask" "F.Paste")
			(net "TP_CPU1_RSVD_105")
		)
		(pad "CE82" smd circle
			(at 33.816544 4.796028)
			(size 0.4318 0.4318)
			(layers "F.Cu" "F.Mask" "F.Paste")
			(net "GND")
		)
		(pad "CE84" smd circle
			(at 35.533584 4.796028)
			(size 0.4318 0.4318)
			(layers "F.Cu" "F.Mask" "F.Paste")
			(net "PVCCIN_CPU1")
		)
		(pad "CF3" smd circle
			(at -35.533584 7.091172)
			(size 0.4318 0.4318)
			(layers "F.Cu" "F.Mask" "F.Paste")
			(net "TP_P3E_CPU1_PE2_RSR_TXN<7>")
		)
		(pad "CF5" smd circle
			(at -33.816544 7.091172)
			(size 0.4318 0.4318)
			(layers "F.Cu" "F.Mask" "F.Paste")
			(net "PVCCIO_CPU1")
		)
	)
)
